(kicad_pcb
	(version 20260206)
	(generator "pcbnew")
	(generator_version "10.0")
	(general
		(thickness 1.6)
		(legacy_teardrops no)
	)
	(paper "A4")
	(title_block
		(title "01162023_DA0F0TEBIF0_F0T_Expander_BD_F_brd_V02_OCP.brd")
		(comment 1 "Grand Teton / footprints 5991-5995 of 9728")
	)
	(layers
		(0 "F.Cu" signal "TOP")
		(4 "In1.Cu" signal "GND")
		(6 "In2.Cu" signal "VCC")
		(8 "In3.Cu" signal "VCC1")
		(10 "In4.Cu" signal "GND1")
		(12 "In5.Cu" signal "IN1")
		(14 "In6.Cu" signal "GND2")
		(16 "In7.Cu" signal "IN2")
		(18 "In8.Cu" signal "GND3")
		(20 "In9.Cu" signal "IN3")
		(22 "In10.Cu" signal "GND4")
		(24 "In11.Cu" signal "IN4")
		(26 "In12.Cu" signal "GND5")
		(28 "In13.Cu" signal "IN5")
		(30 "In14.Cu" signal "GND6")
		(32 "In15.Cu" signal "IN6")
		(34 "In16.Cu" signal "GND7")
		(2 "B.Cu" signal "BOTTOM")
		(9 "F.Adhes" user "F.Adhesive")
		(11 "B.Adhes" user "B.Adhesive")
		(13 "F.Paste" user "Package Geometry/Pastemask Top")
		(15 "B.Paste" user "Package Geometry/Pastemask Bottom")
		(5 "F.SilkS" user "Ref Des/Silkscreen Top")
		(7 "B.SilkS" user "Ref Des/Silkscreen Bottom")
		(1 "F.Mask" user "Board Geometry/Soldermask Top")
		(3 "B.Mask" user "Board Geometry/Soldermask Bottom")
		(17 "Dwgs.User" user "User.Drawings")
		(19 "Cmts.User" user "User.Comments")
		(21 "Eco1.User" user "User.Eco1")
		(23 "Eco2.User" user "User.Eco2")
		(25 "Edge.Cuts" user "Board Geometry/Outline")
		(27 "Margin" user)
		(31 "F.CrtYd" user "Package Geometry/Place Bound Top")
		(29 "B.CrtYd" user "Package Geometry/Place Bound Bottom")
		(35 "F.Fab" user "Ref Des/Assembly Top")
		(33 "B.Fab" user "Ref Des/Assembly Bottom")
	)
	(footprint ""
		(layer "F.Cu")
		(at 294.973248 -84.238592)
		(property "Reference" "U7"
			(at -0.536448 -3.237738 0)
			(unlocked yes)
			(layer "F.SilkS")
			(effects
				(font
					(size 0.7874 0.5842)
					(thickness 0.1524)
				)
				(justify left)
			)
		)
		(property "Value" ""
			(at 0 0 0)
			(layer "F.Fab")
			(effects
				(font
					(size 1.27 1.27)
				)
			)
		)
		(duplicate_pad_numbers_are_jumpers no)
		(fp_line
			(start -1.4224 -2.5146)
			(end -1.4224 2.5146)
			(stroke
				(width 0.1524)
				(type default)
			)
			(layer "F.SilkS")
		)
		(fp_line
			(start -1.4224 2.5146)
			(end 1.4224 2.5146)
			(stroke
				(width 0.1524)
				(type default)
			)
			(layer "F.SilkS")
		)
		(fp_line
			(start -0.4572 -2.5146)
			(end -1.4224 -2.5146)
			(stroke
				(width 0.1524)
				(type default)
			)
			(layer "F.SilkS")
		)
		(fp_line
			(start 0 -2.0574)
			(end -0.4572 -2.5146)
			(stroke
				(width 0.1524)
				(type default)
			)
			(layer "F.SilkS")
		)
		(fp_line
			(start 0.4572 -2.5146)
			(end 0 -2.0574)
			(stroke
				(width 0.1524)
				(type default)
			)
			(layer "F.SilkS")
		)
		(fp_line
			(start 1.4224 -2.5146)
			(end 0.4572 -2.5146)
			(stroke
				(width 0.1524)
				(type default)
			)
			(layer "F.SilkS")
		)
		(fp_line
			(start 1.4224 2.5146)
			(end 1.4224 -2.5146)
			(stroke
				(width 0.1524)
				(type default)
			)
			(layer "F.SilkS")
		)
		(fp_poly
			(pts
				(xy -4.30911 -1.833372) (xy -5.07111 -1.452372) (xy -5.07111 -2.214372)
			)
			(stroke
				(width 0)
				(type default)
			)
			(fill yes)
			(layer "F.SilkS")
		)
		(fp_line
			(start -2.648712 -2.114804)
			(end -2.648712 2.112264)
			(stroke
				(width 0.1)
				(type default)
			)
			(layer "F.Fab")
		)
		(fp_line
			(start -2.648712 2.112264)
			(end -2.0066 2.112264)
			(stroke
				(width 0.1)
				(type default)
			)
			(layer "F.Fab")
		)
		(fp_line
			(start -2.0066 -2.5146)
			(end -2.0066 -2.114804)
			(stroke
				(width 0.1)
				(type default)
			)
			(layer "F.Fab")
		)
		(fp_line
			(start -2.0066 -2.114804)
			(end -2.648712 -2.114804)
			(stroke
				(width 0.1)
				(type default)
			)
			(layer "F.Fab")
		)
		(fp_line
			(start -2.0066 2.112264)
			(end -2.0066 2.5146)
			(stroke
				(width 0.1)
				(type default)
			)
			(layer "F.Fab")
		)
		(fp_line
			(start -2.0066 2.5146)
			(end 2.0066 2.5146)
			(stroke
				(width 0.1)
				(type default)
			)
			(layer "F.Fab")
		)
		(fp_line
			(start 2.0066 -2.5146)
			(end -2.0066 -2.5146)
			(stroke
				(width 0.1)
				(type default)
			)
			(layer "F.Fab")
		)
		(fp_line
			(start 2.0066 -2.112264)
			(end 2.0066 -2.5146)
			(stroke
				(width 0.1)
				(type default)
			)
			(layer "F.Fab")
		)
		(fp_line
			(start 2.0066 2.112264)
			(end 2.642616 2.112264)
			(stroke
				(width 0.1)
				(type default)
			)
			(layer "F.Fab")
		)
		(fp_line
			(start 2.0066 2.5146)
			(end 2.0066 2.112264)
			(stroke
				(width 0.1)
				(type default)
			)
			(layer "F.Fab")
		)
		(fp_line
			(start 2.642616 -2.112264)
			(end 2.0066 -2.112264)
			(stroke
				(width 0.1)
				(type default)
			)
			(layer "F.Fab")
		)
		(fp_line
			(start 2.642616 2.112264)
			(end 2.642616 -2.112264)
			(stroke
				(width 0.1)
				(type default)
			)
			(layer "F.Fab")
		)
		(fp_poly
			(pts
				(xy -3.6322 -1.869186) (xy -4.3942 -1.488186) (xy -4.3942 -2.250186)
			)
			(stroke
				(width 0)
				(type default)
			)
			(fill yes)
			(layer "F.Fab")
		)
		(pad "1" smd rect
			(at -2.6416 -1.905 270)
			(size 0.5588 1.7272)
			(layers "F.Cu" "F.Mask" "F.Paste")
			(net "BB_FRU_A0")
		)
		(pad "2" smd rect
			(at -2.6416 -0.635 270)
			(size 0.5588 1.7272)
			(layers "F.Cu" "F.Mask" "F.Paste")
			(net "BB_FRU_A1")
		)
		(pad "3" smd rect
			(at -2.6416 0.635 270)
			(size 0.5588 1.7272)
			(layers "F.Cu" "F.Mask" "F.Paste")
			(net "BB_FRU_A2")
		)
		(pad "4" smd rect
			(at -2.6416 1.905 270)
			(size 0.5588 1.7272)
			(layers "F.Cu" "F.Mask" "F.Paste")
			(net "GND")
		)
		(pad "5" smd rect
			(at 2.6416 1.905 270)
			(size 0.5588 1.7272)
			(layers "F.Cu" "F.Mask" "F.Paste")
			(net "SMB_BMC_FRU_SDA")
		)
		(pad "6" smd rect
			(at 2.6416 0.635 270)
			(size 0.5588 1.7272)
			(layers "F.Cu" "F.Mask" "F.Paste")
			(net "SMB_BMC_FRU_SCL")
		)
		(pad "7" smd rect
			(at 2.6416 -0.635 270)
			(size 0.5588 1.7272)
			(layers "F.Cu" "F.Mask" "F.Paste")
			(net "GND")
		)
		(pad "8" smd rect
			(at 2.6416 -1.905 270)
			(size 0.5588 1.7272)
			(layers "F.Cu" "F.Mask" "F.Paste")
			(net "P3V3_AUX")
		)
	)
	(footprint ""
		(layer "F.Cu")
		(at 362.697014 -387.160008 180)
		(property "Reference" "R6711"
			(at 0 0 180)
			(layer "F.SilkS")
			(hide yes)
			(effects
				(font
					(size 1.27 1.27)
				)
			)
		)
		(property "Value" ""
			(at 0 0 180)
			(layer "F.Fab")
			(effects
				(font
					(size 1.27 1.27)
				)
			)
		)
		(duplicate_pad_numbers_are_jumpers no)
		(fp_line
			(start 0.7874 0.4064)
			(end -0.7874 0.4064)
			(stroke
				(width 0.1524)
				(type default)
			)
			(layer "F.SilkS")
		)
		(fp_line
			(start 0.7874 -0.4064)
			(end 0.7874 0.4064)
			(stroke
				(width 0.1524)
				(type default)
			)
			(layer "F.SilkS")
		)
		(fp_line
			(start -0.7874 0.4064)
			(end -0.7874 -0.4064)
			(stroke
				(width 0.1524)
				(type default)
			)
			(layer "F.SilkS")
		)
		(fp_line
			(start -0.7874 -0.4064)
			(end 0.7874 -0.4064)
			(stroke
				(width 0.1524)
				(type default)
			)
			(layer "F.SilkS")
		)
		(fp_line
			(start 0.67945 0.3048)
			(end 0.120396 0.3048)
			(stroke
				(width 0.1)
				(type default)
			)
			(layer "F.Fab")
		)
		(fp_line
			(start 0.67945 -0.3048)
			(end 0.67945 0.3048)
			(stroke
				(width 0.1)
				(type default)
			)
			(layer "F.Fab")
		)
		(fp_line
			(start 0.12065 -0.2794)
			(end 0.12065 -0.3048)
			(stroke
				(width 0.1)
				(type default)
			)
			(layer "F.Fab")
		)
		(fp_line
			(start 0.12065 -0.3048)
			(end 0.67945 -0.3048)
			(stroke
				(width 0.1)
				(type default)
			)
			(layer "F.Fab")
		)
		(fp_line
			(start 0.120396 0.3048)
			(end 0.120396 0.2794)
			(stroke
				(width 0.1)
				(type default)
			)
			(layer "F.Fab")
		)
		(fp_line
			(start 0.120396 0.2794)
			(end -0.12065 0.2794)
			(stroke
				(width 0.1)
				(type default)
			)
			(layer "F.Fab")
		)
		(fp_line
			(start -0.12065 0.3048)
			(end -0.67945 0.3048)
			(stroke
				(width 0.1)
				(type default)
			)
			(layer "F.Fab")
		)
		(fp_line
			(start -0.12065 0.2794)
			(end -0.12065 0.3048)
			(stroke
				(width 0.1)
				(type default)
			)
			(layer "F.Fab")
		)
		(fp_line
			(start -0.12065 -0.2794)
			(end 0.12065 -0.2794)
			(stroke
				(width 0.1)
				(type default)
			)
			(layer "F.Fab")
		)
		(fp_line
			(start -0.12065 -0.305054)
			(end -0.12065 -0.2794)
			(stroke
				(width 0.1)
				(type default)
			)
			(layer "F.Fab")
		)
		(fp_line
			(start -0.67945 0.3048)
			(end -0.67945 -0.305054)
			(stroke
				(width 0.1)
				(type default)
			)
			(layer "F.Fab")
		)
		(fp_line
			(start -0.67945 -0.305054)
			(end -0.12065 -0.305054)
			(stroke
				(width 0.1)
				(type default)
			)
			(layer "F.Fab")
		)
		(pad "1" smd circle
			(at -0.40005 0 180)
			(size 0 0)
			(layers "F.Cu" "F.Mask" "F.Paste")
			(net "MB_3V3IO_RSVD4")
		)
		(pad "2" smd circle
			(at 0.40005 0 180)
			(size 0 0)
			(layers "F.Cu" "F.Mask" "F.Paste")
			(net "GND")
		)
	)
	(footprint ""
		(layer "F.Cu")
		(at 340.561422 -198.54545 180)
		(property "Reference" "R4233"
			(at 0 0 180)
			(layer "F.SilkS")
			(hide yes)
			(effects
				(font
					(size 1.27 1.27)
				)
			)
		)
		(property "Value" ""
			(at 0 0 180)
			(layer "F.Fab")
			(effects
				(font
					(size 1.27 1.27)
				)
			)
		)
		(duplicate_pad_numbers_are_jumpers no)
		(fp_line
			(start 0.7874 0.4064)
			(end -0.7874 0.4064)
			(stroke
				(width 0.1524)
				(type default)
			)
			(layer "F.SilkS")
		)
		(fp_line
			(start 0.7874 -0.4064)
			(end 0.7874 0.4064)
			(stroke
				(width 0.1524)
				(type default)
			)
			(layer "F.SilkS")
		)
		(fp_line
			(start -0.7874 0.4064)
			(end -0.7874 -0.4064)
			(stroke
				(width 0.1524)
				(type default)
			)
			(layer "F.SilkS")
		)
		(fp_line
			(start -0.7874 -0.4064)
			(end 0.7874 -0.4064)
			(stroke
				(width 0.1524)
				(type default)
			)
			(layer "F.SilkS")
		)
		(fp_line
			(start 0.67945 0.3048)
			(end 0.120396 0.3048)
			(stroke
				(width 0.1)
				(type default)
			)
			(layer "F.Fab")
		)
		(fp_line
			(start 0.67945 -0.3048)
			(end 0.67945 0.3048)
			(stroke
				(width 0.1)
				(type default)
			)
			(layer "F.Fab")
		)
		(fp_line
			(start 0.12065 -0.2794)
			(end 0.12065 -0.3048)
			(stroke
				(width 0.1)
				(type default)
			)
			(layer "F.Fab")
		)
		(fp_line
			(start 0.12065 -0.3048)
			(end 0.67945 -0.3048)
			(stroke
				(width 0.1)
				(type default)
			)
			(layer "F.Fab")
		)
		(fp_line
			(start 0.120396 0.3048)
			(end 0.120396 0.2794)
			(stroke
				(width 0.1)
				(type default)
			)
			(layer "F.Fab")
		)
		(fp_line
			(start 0.120396 0.2794)
			(end -0.12065 0.2794)
			(stroke
				(width 0.1)
				(type default)
			)
			(layer "F.Fab")
		)
		(fp_line
			(start -0.12065 0.3048)
			(end -0.67945 0.3048)
			(stroke
				(width 0.1)
				(type default)
			)
			(layer "F.Fab")
		)
		(fp_line
			(start -0.12065 0.2794)
			(end -0.12065 0.3048)
			(stroke
				(width 0.1)
				(type default)
			)
			(layer "F.Fab")
		)
		(fp_line
			(start -0.12065 -0.2794)
			(end 0.12065 -0.2794)
			(stroke
				(width 0.1)
				(type default)
			)
			(layer "F.Fab")
		)
		(fp_line
			(start -0.12065 -0.305054)
			(end -0.12065 -0.2794)
			(stroke
				(width 0.1)
				(type default)
			)
			(layer "F.Fab")
		)
		(fp_line
			(start -0.67945 0.3048)
			(end -0.67945 -0.305054)
			(stroke
				(width 0.1)
				(type default)
			)
			(layer "F.Fab")
		)
		(fp_line
			(start -0.67945 -0.305054)
			(end -0.12065 -0.305054)
			(stroke
				(width 0.1)
				(type default)
			)
			(layer "F.Fab")
		)
		(pad "1" smd circle
			(at -0.40005 0 180)
			(size 0 0)
			(layers "F.Cu" "F.Mask" "F.Paste")
			(net "SMB_FIO_R1_SDA")
		)
		(pad "2" smd circle
			(at 0.40005 0 180)
			(size 0 0)
			(layers "F.Cu" "F.Mask" "F.Paste")
			(net "SMB_IO_DEBUG_CARD_R_SDA")
		)
	)
	(footprint ""
		(layer "F.Cu")
		(at 240.35258 -222.064072)
		(property "Reference" "C3613"
			(at 0 0 0)
			(layer "F.SilkS")
			(hide yes)
			(effects
				(font
					(size 1.27 1.27)
				)
			)
		)
		(property "Value" ""
			(at 0 0 0)
			(layer "F.Fab")
			(effects
				(font
					(size 1.27 1.27)
				)
			)
		)
		(duplicate_pad_numbers_are_jumpers no)
		(fp_line
			(start -0.69215 -0.2921)
			(end 0.69215 -0.2921)
			(stroke
				(width 0.1524)
				(type default)
			)
			(layer "F.SilkS")
		)
		(fp_line
			(start -0.69215 0.2921)
			(end -0.69215 -0.2921)
			(stroke
				(width 0.1524)
				(type default)
			)
			(layer "F.SilkS")
		)
		(fp_line
			(start 0.69215 -0.2921)
			(end 0.69215 0.2921)
			(stroke
				(width 0.1524)
				(type default)
			)
			(layer "F.SilkS")
		)
		(fp_line
			(start 0.69215 0.2921)
			(end -0.69215 0.2921)
			(stroke
				(width 0.1524)
				(type default)
			)
			(layer "F.SilkS")
		)
		(fp_line
			(start -0.51435 -0.2794)
			(end 0.51435 -0.2794)
			(stroke
				(width 0.1)
				(type default)
			)
			(layer "F.Fab")
		)
		(fp_line
			(start -0.51435 0.2794)
			(end -0.51435 -0.2794)
			(stroke
				(width 0.1)
				(type default)
			)
			(layer "F.Fab")
		)
		(fp_line
			(start 0.51435 -0.2794)
			(end 0.51435 0.2794)
			(stroke
				(width 0.1)
				(type default)
			)
			(layer "F.Fab")
		)
		(fp_line
			(start 0.51435 0.2794)
			(end -0.51435 0.2794)
			(stroke
				(width 0.1)
				(type default)
			)
			(layer "F.Fab")
		)
		(pad "1" smd circle
			(at -0.40005 0)
			(size 0 0)
			(layers "F.Cu" "F.Mask" "F.Paste")
			(net "P1V2_BIC_ADCVREFREXT1")
		)
		(pad "2" smd circle
			(at 0.40005 0)
			(size 0 0)
			(layers "F.Cu" "F.Mask" "F.Paste")
			(net "GND")
		)
		(zone
			(layer "F.Cu")
			(hatch none 0.5)
			(connect_pads
				(clearance 0)
			)
			(min_thickness 0.25)
			(keepout
				(tracks not_allowed)
				(vias allowed)
				(pads allowed)
				(copperpour not_allowed)
				(footprints allowed)
			)
			(placement
				(enabled no)
				(sheetname "")
			)
			(fill
				(thermal_gap 0.5)
				(thermal_bridge_width 0.5)
				(island_removal_mode 0)
			)
			(polygon
				(pts
					(xy 240.16208 -221.976442) (xy 240.25352 -221.918276) (xy 240.45291 -221.918276) (xy 240.54308 -221.976442)
					(xy 240.54308 -222.151702) (xy 240.45291 -222.210122) (xy 240.25352 -222.210122) (xy 240.16208 -222.151956)
				)
			)
		)
	)
	(footprint ""
		(layer "F.Cu")
		(at 243.434108 -137.01776 180)
		(property "Reference" "PU23"
			(at 2.611374 -2.796286 0)
			(unlocked yes)
			(layer "F.SilkS")
			(effects
				(font
					(size 0.7874 0.5842)
					(thickness 0.1524)
				)
				(justify left)
			)
		)
		(property "Value" ""
			(at 0 0 180)
			(layer "F.Fab")
			(effects
				(font
					(size 1.27 1.27)
				)
			)
		)
		(duplicate_pad_numbers_are_jumpers no)
		(fp_line
			(start 1.943608 1.549908)
			(end -1.943608 1.549908)
			(stroke
				(width 0.1524)
				(type default)
			)
			(layer "F.SilkS")
		)
		(fp_line
			(start 1.943608 -1.549908)
			(end 1.943608 1.549908)
			(stroke
				(width 0.1524)
				(type default)
			)
			(layer "F.SilkS")
		)
		(fp_line
			(start -1.943608 1.549908)
			(end -1.943608 -1.549908)
			(stroke
				(width 0.1524)
				(type default)
			)
			(layer "F.SilkS")
		)
		(fp_line
			(start -1.943608 -1.549908)
			(end 1.943608 -1.549908)
			(stroke
				(width 0.1524)
				(type default)
			)
			(layer "F.SilkS")
		)
		(fp_poly
			(pts
				(xy -2.019808 -1.549908) (xy -1.257808 -1.549908) (xy -1.257808 -1.880108) (xy -2.019808 -1.880108)
			)
			(stroke
				(width 0)
				(type default)
			)
			(fill yes)
			(layer "F.SilkS")
		)
		(fp_line
			(start 1.549908 1.549908)
			(end -1.549908 1.549908)
			(stroke
				(width 0.1)
				(type default)
			)
			(layer "F.Fab")
		)
		(fp_line
			(start 1.549908 -1.549908)
			(end 1.549908 1.549908)
			(stroke
				(width 0.1)
				(type default)
			)
			(layer "F.Fab")
		)
		(fp_line
			(start -1.549908 1.549908)
			(end -1.549908 -1.549908)
			(stroke
				(width 0.1)
				(type default)
			)
			(layer "F.Fab")
		)
		(fp_line
			(start -1.549908 -1.549908)
			(end 1.549908 -1.549908)
			(stroke
				(width 0.1)
				(type default)
			)
			(layer "F.Fab")
		)
		(fp_poly
			(pts
				(xy -2.019808 -1.549908) (xy -1.257808 -1.549908) (xy -1.257808 -1.880108) (xy -2.019808 -1.880108)
			)
			(stroke
				(width 0)
				(type default)
			)
			(fill yes)
			(layer "F.Fab")
		)
		(pad "1" smd rect
			(at -1.500124 -1.249934 90)
			(size 0.2794 0.6096)
			(layers "F.Cu" "F.Mask" "F.Paste")
			(net "P12V_NIC4_R")
		)
		(pad "2" smd rect
			(at -1.500124 -0.750062 90)
			(size 0.2794 0.6096)
			(layers "F.Cu" "F.Mask" "F.Paste")
			(net "P12V_NIC4_R")
		)
		(pad "3" smd rect
			(at -1.500124 -0.249936 90)
			(size 0.2794 0.6096)
			(layers "F.Cu" "F.Mask" "F.Paste")
			(net "P12V_NIC4_R")
		)
		(pad "4" smd rect
			(at -1.500124 0.249936 90)
			(size 0.2794 0.6096)
			(layers "F.Cu" "F.Mask" "F.Paste")
			(net "P12V_NIC4_R")
		)
		(pad "5" smd rect
			(at -1.500124 0.750062 90)
			(size 0.2794 0.6096)
			(layers "F.Cu" "F.Mask" "F.Paste")
			(net "P12V_NIC4_R")
		)
		(pad "6" smd rect
			(at -1.500124 1.249934 90)
			(size 0.2794 0.6096)
			(layers "F.Cu" "F.Mask" "F.Paste")
			(net "GND")
		)
		(pad "7" smd rect
			(at 1.500124 1.249934 90)
			(size 0.2794 0.6096)
			(layers "F.Cu" "F.Mask" "F.Paste")
			(net "P12V_NIC4_SS")
		)
		(pad "8" smd rect
			(at 1.500124 0.750062 90)
			(size 0.2794 0.6096)
			(layers "F.Cu" "F.Mask" "F.Paste")
			(net "PWRGD_P12V_NIC4")
		)
		(pad "9" smd rect
			(at 1.500124 0.249936 90)
			(size 0.2794 0.6096)
			(layers "F.Cu" "F.Mask" "F.Paste")
			(net "P12V_NIC4_OCP")
		)
		(pad "10" smd rect
			(at 1.500124 -0.249936 90)
			(size 0.2794 0.6096)
			(layers "F.Cu" "F.Mask" "F.Paste")
			(net "P5V_AUX")
		)
		(pad "11" smd rect
			(at 1.500124 -0.750062 90)
			(size 0.2794 0.6096)
			(layers "F.Cu" "F.Mask" "F.Paste")
			(net "P12V_NIC4_EN_R")
		)
		(pad "12" smd rect
			(at 1.500124 -1.249934 90)
			(size 0.2794 0.6096)
			(layers "F.Cu" "F.Mask" "F.Paste")
			(net "P12V_AUX")
		)
		(pad "13" smd rect
			(at 0 0 180)
			(size 1.9812 2.7178)
			(layers "F.Cu" "F.Mask" "F.Paste")
			(net "P12V_AUX")
		)
		(zone
			(layer "F.Cu")
			(hatch none 0.5)
			(connect_pads
				(clearance 0)
			)
			(min_thickness 0.25)
			(keepout
				(tracks not_allowed)
				(vias allowed)
				(pads allowed)
				(copperpour not_allowed)
				(footprints allowed)
			)
			(placement
				(enabled no)
				(sheetname "")
			)
			(fill
				(thermal_gap 0.5)
				(thermal_bridge_width 0.5)
				(island_removal_mode 0)
			)
			(polygon
				(pts
					(xy 242.291108 -135.46836) (xy 242.291108 -135.59536) (xy 242.291108 -138.56716) (xy 242.291108 -138.567668)
					(xy 244.577108 -138.567668) (xy 244.577108 -138.56716) (xy 244.577108 -138.44016) (xy 244.577108 -137.01776)
					(xy 244.475508 -137.01776) (xy 244.475508 -138.44016) (xy 242.392708 -138.44016) (xy 242.392708 -135.59536)
					(xy 244.475508 -135.59536) (xy 244.475508 -136.99236) (xy 244.577108 -136.99236) (xy 244.577108 -135.59536)
					(xy 244.577108 -135.46836) (xy 244.577108 -135.467852) (xy 242.291108 -135.467852)
				)
			)
		)
	)
)
